(kicad_pcb
	(version 20241229)
	(generator "pcbnew")
	(generator_version "9.0")
	(general
		(thickness 1.711)
		(legacy_teardrops no)
	)
	(paper "A4")
	(title_block
		(title "Antmicro Baseboard for Jetson AGX Thor")
		(date "2026-02-18")
		(rev "1.1.0")
		(company "Antmicro Ltd")
		(comment 1 "www.antmicro.com")
		(comment 9 "footprints 748-751 of 1170")
	)
	(layers
		(0 "F.Cu" signal)
		(4 "In1.Cu" signal)
		(6 "In2.Cu" signal)
		(8 "In3.Cu" signal)
		(10 "In4.Cu" jumper)
		(12 "In5.Cu" signal)
		(14 "In6.Cu" signal)
		(16 "In7.Cu" signal)
		(18 "In8.Cu" signal)
		(2 "B.Cu" signal)
		(9 "F.Adhes" user "F.Adhesive")
		(11 "B.Adhes" user "B.Adhesive")
		(13 "F.Paste" user)
		(15 "B.Paste" user)
		(5 "F.SilkS" user "F.Silkscreen")
		(7 "B.SilkS" user "B.Silkscreen")
		(1 "F.Mask" user)
		(3 "B.Mask" user)
		(17 "Dwgs.User" user "User.Drawings")
		(19 "Cmts.User" user "User.Comments")
		(21 "Eco1.User" user "User.Eco1")
		(23 "Eco2.User" user "User.Eco2")
		(25 "Edge.Cuts" user)
		(27 "Margin" user)
		(31 "F.CrtYd" user "F.Courtyard")
		(29 "B.CrtYd" user "B.Courtyard")
		(35 "F.Fab" user)
		(33 "B.Fab" user)
	)
	(footprint "antmicro-footprints:QFN-16-1EP_4x4mm_P0.65mm"
		(layer "B.Cu")
		(at 220 78.34 -90)
		(property "Reference" "U34"
			(at 2.49 2.32 0)
			(layer "B.SilkS")
			(effects
				(font
					(size 0.7 0.7)
					(thickness 0.15)
				)
				(justify left bottom mirror)
			)
		)
		(property "Value" "FT230X_QFN"
			(at 0 -3.3 90)
			(layer "B.Fab")
			(effects
				(font
					(size 0.7 0.7)
					(thickness 0.15)
				)
				(justify left bottom mirror)
			)
		)
		(property "Datasheet" "https://ftdichip.com/wp-content/uploads/2021/10/DS_FT230X.pdf"
			(at 0 0 90)
			(layer "B.Fab")
			(hide yes)
			(effects
				(font
					(size 1.27 1.27)
					(thickness 0.15)
				)
				(justify mirror)
			)
		)
		(property "Description" "USB Interface, USB-UART Converter, USB 2.0, 2.97 V, 5.5 V, QFN, 16 Pins"
			(at 0 0 90)
			(layer "B.Fab")
			(hide yes)
			(effects
				(font
					(size 1.27 1.27)
					(thickness 0.15)
				)
				(justify mirror)
			)
		)
		(property "Manufacturer" "FTDI Chip"
			(at 0 0 90)
			(unlocked yes)
			(layer "B.Fab")
			(hide yes)
			(effects
				(font
					(size 1 1)
					(thickness 0.15)
				)
				(justify mirror)
			)
		)
		(property "MPN" "FT230XQ-R"
			(at 0 0 90)
			(unlocked yes)
			(layer "B.Fab")
			(hide yes)
			(effects
				(font
					(size 1 1)
					(thickness 0.15)
				)
				(justify mirror)
			)
		)
		(property "Author" "Antmicro"
			(at 0 0 90)
			(unlocked yes)
			(layer "B.Fab")
			(hide yes)
			(effects
				(font
					(size 1 1)
					(thickness 0.15)
				)
				(justify mirror)
			)
		)
		(property "License" "Apache-2.0"
			(at 0 0 90)
			(unlocked yes)
			(layer "B.Fab")
			(hide yes)
			(effects
				(font
					(size 1 1)
					(thickness 0.15)
				)
				(justify mirror)
			)
		)
		(sheetname "/USB Debug, PD/")
		(sheetfile "usb_debug_pd.kicad_sch")
		(attr smd)
		(fp_line
			(start 1.499 2.101)
			(end 2.1 2.101)
			(stroke
				(width 0.15)
				(type solid)
			)
			(layer "B.SilkS")
		)
		(fp_line
			(start 2.1 2.101)
			(end 2.1 1.401)
			(stroke
				(width 0.15)
				(type solid)
			)
			(layer "B.SilkS")
		)
		(fp_line
			(start -2.1 2.1)
			(end -2.101 1.4)
			(stroke
				(width 0.15)
				(type solid)
			)
			(layer "B.SilkS")
		)
		(fp_line
			(start -1.4 2.1)
			(end -2.1 2.1)
			(stroke
				(width 0.15)
				(type solid)
			)
			(layer "B.SilkS")
		)
		(fp_line
			(start -2.101 -1.398)
			(end -2.101 -2.1)
			(stroke
				(width 0.15)
				(type solid)
			)
			(layer "B.SilkS")
		)
		(fp_line
			(start -2.101 -2.1)
			(end -1.5 -2.1)
			(stroke
				(width 0.15)
				(type solid)
			)
			(layer "B.SilkS")
		)
		(fp_line
			(start 1.499 -2.1)
			(end 2.1 -2.1)
			(stroke
				(width 0.15)
				(type solid)
			)
			(layer "B.SilkS")
		)
		(fp_line
			(start 2.1 -2.1)
			(end 2.1 -1.398)
			(stroke
				(width 0.15)
				(type solid)
			)
			(layer "B.SilkS")
		)
		(fp_circle
			(center -2.35 1.4)
			(end -2.3 1.4)
			(stroke
				(width 0.15)
				(type solid)
			)
			(fill yes)
			(layer "B.SilkS")
		)
		(fp_rect
			(start -2.35 2.35)
			(end 2.35 -2.35)
			(stroke
				(width 0.05)
				(type solid)
			)
			(fill no)
			(layer "B.CrtYd")
		)
		(fp_line
			(start -1.5 2)
			(end -2 1.5)
			(stroke
				(width 0.15)
				(type solid)
			)
			(layer "B.Fab")
		)
		(fp_rect
			(start 2 -2)
			(end -2 2)
			(stroke
				(width 0.15)
				(type solid)
			)
			(fill no)
			(layer "B.Fab")
		)
		(fp_text user "Author: Antmicro"
			(at -2.35 -6.799 90)
			(layer "B.Fab")
			(effects
				(font
					(size 0.7 0.7)
					(thickness 0.15)
				)
				(justify left bottom mirror)
			)
		)
		(fp_text user "License: Apache-2.0"
			(at -2.35 -7.999 90)
			(layer "B.Fab")
			(effects
				(font
					(size 0.7 0.7)
					(thickness 0.15)
				)
				(justify left bottom mirror)
			)
		)
		(fp_text user "${REFERENCE}"
			(at -2.35 -5.599 90)
			(layer "B.Fab")
			(effects
				(font
					(size 0.7 0.7)
					(thickness 0.15)
				)
				(justify left bottom mirror)
			)
		)
		(pad "1" smd rect
			(at -1.9 0.975 270)
			(size 0.8 0.4)
			(layers "B.Cu" "B.Mask" "B.Paste")
			(net 334 "/USB Debug, PD/FTDI_3V3")
			(pinfunction "V_{CCIO}")
			(pintype "power_in")
		)
		(pad "2" smd rect
			(at -1.9 0.325 270)
			(size 0.8 0.4)
			(layers "B.Cu" "B.Mask" "B.Paste")
			(net 961 "Net-(U34-RXD)")
			(pinfunction "RXD")
			(pintype "input")
		)
		(pad "3" smd rect
			(at -1.9 -0.325 270)
			(size 0.8 0.4)
			(layers "B.Cu" "B.Mask" "B.Paste")
			(net 1 "GND")
			(pinfunction "GND")
			(pintype "passive")
		)
		(pad "4" smd rect
			(at -1.9 -0.975 270)
			(size 0.8 0.4)
			(layers "B.Cu" "B.Mask" "B.Paste")
			(net 1115 "unconnected-(U34-~{CTS}-Pad4)")
			(pinfunction "~{CTS}")
			(pintype "input+no_connect")
		)
		(pad "5" smd rect
			(at -0.975 -1.9 270)
			(size 0.4 0.8)
			(layers "B.Cu" "B.Mask" "B.Paste")
			(net 536 "/USB Debug, PD/FTDI_LED_TX")
			(pinfunction "CBUS2")
			(pintype "bidirectional")
		)
		(pad "6" smd rect
			(at -0.325 -1.9 270)
			(size 0.4 0.8)
			(layers "B.Cu" "B.Mask" "B.Paste")
			(net 973 "/USB Debug, PD/USB_FTDI_P")
			(pinfunction "D+")
			(pintype "input")
		)
		(pad "7" smd rect
			(at 0.325 -1.9 270)
			(size 0.4 0.8)
			(layers "B.Cu" "B.Mask" "B.Paste")
			(net 974 "/USB Debug, PD/USB_FTDI_N")
			(pinfunction "D-")
			(pintype "input")
		)
		(pad "8" smd rect
			(at 0.975 -1.9 270)
			(size 0.4 0.8)
			(layers "B.Cu" "B.Mask" "B.Paste")
			(net 334 "/USB Debug, PD/FTDI_3V3")
			(pinfunction "3V3_{OUT}")
			(pintype "passive")
		)
		(pad "9" smd rect
			(at 1.9 -0.975 270)
			(size 0.8 0.4)
			(layers "B.Cu" "B.Mask" "B.Paste")
			(net 339 "Net-(U34-~{RESET})")
			(pinfunction "~{RESET}")
			(pintype "input")
		)
		(pad "10" smd rect
			(at 1.9 -0.325 270)
			(size 0.8 0.4)
			(layers "B.Cu" "B.Mask" "B.Paste")
			(net 334 "/USB Debug, PD/FTDI_3V3")
			(pinfunction "V_{CC}")
			(pintype "power_in")
		)
		(pad "11" smd rect
			(at 1.9 0.325 270)
			(size 0.8 0.4)
			(layers "B.Cu" "B.Mask" "B.Paste")
			(net 537 "/USB Debug, PD/FTDI_LED_RX")
			(pinfunction "CBUS1")
			(pintype "bidirectional")
		)
		(pad "12" smd rect
			(at 1.9 0.975 270)
			(size 0.8 0.4)
			(layers "B.Cu" "B.Mask" "B.Paste")
			(net 956 "/USB Debug, PD/FTDI_CBUS0{slash}SDA")
			(pinfunction "CBUS0")
			(pintype "bidirectional")
		)
		(pad "13" smd rect
			(at 0.975 1.9 270)
			(size 0.4 0.8)
			(layers "B.Cu" "B.Mask" "B.Paste")
			(net 1 "GND")
			(pinfunction "GND")
			(pintype "power_in")
		)
		(pad "14" smd rect
			(at 0.325 1.9 270)
			(size 0.4 0.8)
			(layers "B.Cu" "B.Mask" "B.Paste")
			(net 955 "/USB Debug, PD/FTDI_CBUS3{slash}SCL")
			(pinfunction "CBUS3")
			(pintype "bidirectional")
		)
		(pad "15" smd rect
			(at -0.325 1.9 270)
			(size 0.4 0.8)
			(layers "B.Cu" "B.Mask" "B.Paste")
			(net 958 "Net-(U34-TXD)")
			(pinfunction "TXD")
			(pintype "output")
		)
		(pad "16" smd rect
			(at -0.975 1.9 270)
			(size 0.4 0.8)
			(layers "B.Cu" "B.Mask" "B.Paste")
			(net 1114 "unconnected-(U34-~{RTS}-Pad16)")
			(pinfunction "~{RTS}")
			(pintype "output+no_connect")
		)
		(pad "17" smd rect
			(at 0 0 270)
			(size 2.3 2.3)
			(layers "B.Cu" "B.Mask" "B.Paste")
			(net 1 "GND")
			(pinfunction "GND")
			(pintype "passive")
		)
	)
	(footprint "antmicro-footprints:R_0402_1005Metric"
		(layer "B.Cu")
		(at 157.15 68.55 180)
		(descr "Resistor SMD 0402")
		(tags "resistor SMD 0402")
		(property "Reference" "R295"
			(at -1.07 -4.15 0)
			(layer "B.SilkS")
			(effects
				(font
					(size 0.7 0.7)
					(thickness 0.15)
				)
				(justify left bottom mirror)
			)
		)
		(property "Value" "R_0R_0402"
			(at -1.011843 -1.772047 0)
			(layer "B.Fab")
			(effects
				(font
					(size 0.7 0.7)
					(thickness 0.15)
				)
				(justify left bottom mirror)
			)
		)
		(property "Datasheet" "https://industrial.panasonic.com/cdbs/www-data/pdf/RDA0000/AOA0000C301.pdf"
			(at 0 0 0)
			(layer "B.Fab")
			(hide yes)
			(effects
				(font
					(size 1.27 1.27)
					(thickness 0.15)
				)
				(justify mirror)
			)
		)
		(property "Description" "SMD Chip Resistor, Jumper, 0 ohm, 100 mW, 0402 [1005 Metric], Thick Film, General Purpose"
			(at 0 0 0)
			(layer "B.Fab")
			(hide yes)
			(effects
				(font
					(size 1.27 1.27)
					(thickness 0.15)
				)
				(justify mirror)
			)
		)
		(property "MPN" "ERJ2GE0R00X"
			(at 0 0 0)
			(unlocked yes)
			(layer "B.Fab")
			(hide yes)
			(effects
				(font
					(size 1 1)
					(thickness 0.15)
				)
				(justify mirror)
			)
		)
		(property "Manufacturer" "Panasonic"
			(at 0 0 0)
			(unlocked yes)
			(layer "B.Fab")
			(hide yes)
			(effects
				(font
					(size 1 1)
					(thickness 0.15)
				)
				(justify mirror)
			)
		)
		(property "License" "Apache-2.0"
			(at 0 0 0)
			(unlocked yes)
			(layer "B.Fab")
			(hide yes)
			(effects
				(font
					(size 1 1)
					(thickness 0.15)
				)
				(justify mirror)
			)
		)
		(property "Author" "Antmicro"
			(at 0 0 0)
			(unlocked yes)
			(layer "B.Fab")
			(hide yes)
			(effects
				(font
					(size 1 1)
					(thickness 0.15)
				)
				(justify mirror)
			)
		)
		(property "Val" "0R"
			(at 0 0 0)
			(unlocked yes)
			(layer "B.Fab")
			(hide yes)
			(effects
				(font
					(size 1 1)
					(thickness 0.15)
				)
				(justify mirror)
			)
		)
		(property "Tolerance" "~"
			(at 0 0 0)
			(unlocked yes)
			(layer "B.Fab")
			(hide yes)
			(effects
				(font
					(size 1 1)
					(thickness 0.15)
				)
				(justify mirror)
			)
		)
		(property "Current" "1A"
			(at 0 0 0)
			(unlocked yes)
			(layer "B.Fab")
			(hide yes)
			(effects
				(font
					(size 1 1)
					(thickness 0.15)
				)
				(justify mirror)
			)
		)
		(sheetname "/SoM_IO2/")
		(sheetfile "som_io2.kicad_sch")
		(attr smd exclude_from_pos_files exclude_from_bom dnp)
		(fp_rect
			(start -0.925 0.47)
			(end 0.925 -0.47)
			(stroke
				(width 0.05)
				(type default)
			)
			(fill no)
			(layer "B.CrtYd")
		)
		(fp_rect
			(start -0.5 0.25)
			(end 0.5 -0.25)
			(stroke
				(width 0.15)
				(type solid)
			)
			(fill no)
			(layer "B.Fab")
		)
		(fp_text user "License: Apache-2.0"
			(at -0.95 -5.169 0)
			(layer "B.Fab")
			(effects
				(font
					(size 0.7 0.7)
					(thickness 0.15)
				)
				(justify left bottom mirror)
			)
		)
		(fp_text user "${REFERENCE}"
			(at -0.95 -3.168 0)
			(layer "B.Fab")
			(effects
				(font
					(size 0.7 0.7)
					(thickness 0.15)
				)
				(justify left bottom mirror)
			)
		)
		(fp_text user "Author: Antmicro"
			(at -0.95 -4.169 0)
			(layer "B.Fab")
			(effects
				(font
					(size 0.7 0.7)
					(thickness 0.15)
				)
				(justify left bottom mirror)
			)
		)
		(pad "1" smd roundrect
			(at -0.48 0 180)
			(size 0.59 0.64)
			(layers "B.Cu" "B.Mask" "B.Paste")
			(roundrect_rratio 0.25)
			(net 1031 "Net-(U59-B4)")
			(pintype "passive")
		)
		(pad "2" smd roundrect
			(at 0.48 0 180)
			(size 0.59 0.64)
			(layers "B.Cu" "B.Mask" "B.Paste")
			(roundrect_rratio 0.25)
			(net 688 "/SoM_IO2/JTAG_TDO")
			(pintype "passive")
		)
	)
	(footprint "antmicro-footprints:C_0402_1005Metric"
		(layer "B.Cu")
		(at 221.35 82.3 -90)
		(descr "Capacitor SMD 0402")
		(tags "capacitor SMD 0402")
		(property "Reference" "C140"
			(at 0.9 -0.55 90)
			(layer "B.SilkS")
			(effects
				(font
					(size 0.7 0.7)
					(thickness 0.15)
				)
				(justify left bottom mirror)
			)
		)
		(property "Value" "C_100n_0402"
			(at -1.022927 -2.155213 90)
			(layer "B.Fab")
			(effects
				(font
					(size 0.7 0.7)
					(thickness 0.15)
				)
				(justify left bottom mirror)
			)
		)
		(property "Datasheet" "https://www.murata.com/products/productdetail?partno=GRM155R61H104KE14%23"
			(at 0 0 90)
			(layer "B.Fab")
			(hide yes)
			(effects
				(font
					(size 1.27 1.27)
					(thickness 0.15)
				)
				(justify mirror)
			)
		)
		(property "Description" "SMD Multilayer Ceramic Capacitor, 0.1 µF, 50 V, 0402 [1005 Metric], ± 10%, X5R, GRM Series"
			(at 0 0 90)
			(layer "B.Fab")
			(hide yes)
			(effects
				(font
					(size 1.27 1.27)
					(thickness 0.15)
				)
				(justify mirror)
			)
		)
		(property "Manufacturer" "Murata"
			(at 0 0 90)
			(unlocked yes)
			(layer "B.Fab")
			(hide yes)
			(effects
				(font
					(size 1 1)
					(thickness 0.15)
				)
				(justify mirror)
			)
		)
		(property "MPN" "GRM155R61H104KE14D"
			(at 0 0 90)
			(unlocked yes)
			(layer "B.Fab")
			(hide yes)
			(effects
				(font
					(size 1 1)
					(thickness 0.15)
				)
				(justify mirror)
			)
		)
		(property "Val" "100n"
			(at 0 0 90)
			(unlocked yes)
			(layer "B.Fab")
			(hide yes)
			(effects
				(font
					(size 1 1)
					(thickness 0.15)
				)
				(justify mirror)
			)
		)
		(property "License" "Apache-2.0"
			(at 0 0 90)
			(unlocked yes)
			(layer "B.Fab")
			(hide yes)
			(effects
				(font
					(size 1 1)
					(thickness 0.15)
				)
				(justify mirror)
			)
		)
		(property "Author" "Antmicro"
			(at 0 0 90)
			(unlocked yes)
			(layer "B.Fab")
			(hide yes)
			(effects
				(font
					(size 1 1)
					(thickness 0.15)
				)
				(justify mirror)
			)
		)
		(property "Voltage" "50V"
			(at 0 0 90)
			(unlocked yes)
			(layer "B.Fab")
			(hide yes)
			(effects
				(font
					(size 1 1)
					(thickness 0.15)
				)
				(justify mirror)
			)
		)
		(property "Dielectric" "X5R"
			(at 0 0 90)
			(unlocked yes)
			(layer "B.Fab")
			(hide yes)
			(effects
				(font
					(size 1 1)
					(thickness 0.15)
				)
				(justify mirror)
			)
		)
		(sheetname "/USB Debug, PD/")
		(sheetfile "usb_debug_pd.kicad_sch")
		(attr smd)
		(fp_rect
			(start -0.925 0.47)
			(end 0.925 -0.47)
			(stroke
				(width 0.05)
				(type default)
			)
			(fill no)
			(layer "B.CrtYd")
		)
		(fp_line
			(start -0.494 0.25)
			(end 0.504 0.25)
			(stroke
				(width 0.15)
				(type solid)
			)
			(layer "B.Fab")
		)
		(fp_line
			(start 0.504 0.25)
			(end 0.504 -0.248)
			(stroke
				(width 0.15)
				(type solid)
			)
			(layer "B.Fab")
		)
		(fp_line
			(start -0.494 -0.248)
			(end -0.494 0.25)
			(stroke
				(width 0.15)
				(type solid)
			)
			(layer "B.Fab")
		)
		(fp_line
			(start 0.504 -0.248)
			(end -0.494 -0.248)
			(stroke
				(width 0.15)
				(type solid)
			)
			(layer "B.Fab")
		)
		(fp_text user "${REFERENCE}"
			(at -0.939 -4.599 90)
			(layer "B.Fab")
			(effects
				(font
					(size 0.7 0.7)
					(thickness 0.15)
				)
				(justify left bottom mirror)
			)
		)
		(fp_text user "License: Apache-2.0"
			(at -0.939 -5.799 90)
			(layer "B.Fab")
			(effects
				(font
					(size 0.7 0.7)
					(thickness 0.15)
				)
				(justify left bottom mirror)
			)
		)
		(fp_text user "Author: Antmicro"
			(at -0.939 -3.399 90)
			(layer "B.Fab")
			(effects
				(font
					(size 0.7 0.7)
					(thickness 0.15)
				)
				(justify left bottom mirror)
			)
		)
		(pad "1" smd roundrect
			(at -0.48 0 270)
			(size 0.59 0.64)
			(layers "B.Cu" "B.Mask" "B.Paste")
			(roundrect_rratio 0.25)
			(net 339 "Net-(U34-~{RESET})")
			(pintype "passive")
		)
		(pad "2" smd roundrect
			(at 0.48 0 270)
			(size 0.59 0.64)
			(layers "B.Cu" "B.Mask" "B.Paste")
			(roundrect_rratio 0.25)
			(net 1 "GND")
			(pintype "passive")
		)
	)
	(footprint "antmicro-footprints:TP_SMD_0.75mm"
		(layer "B.Cu")
		(at 198.8 116.4 90)
		(property "Reference" "TP66"
			(at 0.58 -0.33 90)
			(layer "B.SilkS")
			(effects
				(font
					(size 0.7 0.7)
					(thickness 0.15)
				)
				(justify right top mirror)
			)
		)
		(property "Value" "TP_0.75mm_SMD"
			(at 0 -1.2 90)
			(layer "B.Fab")
			(effects
				(font
					(size 0.7 0.7)
					(thickness 0.15)
				)
				(justify right top mirror)
			)
		)
		(property "Description" "SMT test point"
			(at 0 0 90)
			(layer "B.Fab")
			(hide yes)
			(effects
				(font
					(size 1.27 1.27)
					(thickness 0.15)
				)
				(justify mirror)
			)
		)
		(property "MPN" ""
			(at 0 0 270)
			(unlocked yes)
			(layer "B.Fab")
			(hide yes)
			(effects
				(font
					(size 1 1)
					(thickness 0.15)
				)
				(justify mirror)
			)
		)
		(property "Manufacturer" ""
			(at 0 0 270)
			(unlocked yes)
			(layer "B.Fab")
			(hide yes)
			(effects
				(font
					(size 1 1)
					(thickness 0.15)
				)
				(justify mirror)
			)
		)
		(property "Author" "Antmicro"
			(at 0 0 270)
			(unlocked yes)
			(layer "B.Fab")
			(hide yes)
			(effects
				(font
					(size 1 1)
					(thickness 0.15)
				)
				(justify mirror)
			)
		)
		(property "License" "Apache-2.0"
			(at 0 0 270)
			(unlocked yes)
			(layer "B.Fab")
			(hide yes)
			(effects
				(font
					(size 1 1)
					(thickness 0.15)
				)
				(justify mirror)
			)
		)
		(sheetname "/USB Hub/")
		(sheetfile "usb_hub.kicad_sch")
		(attr exclude_from_pos_files exclude_from_bom)
		(fp_circle
			(center 0 0)
			(end 0.475 0)
			(stroke
				(width 0.05)
				(type default)
			)
			(fill no)
			(layer "B.CrtYd")
		)
		(fp_text user "${REFERENCE}"
			(at -0.4 -2.7 90)
			(layer "B.Fab")
			(effects
				(font
					(size 0.7 0.7)
					(thickness 0.15)
				)
				(justify right top mirror)
			)
		)
		(fp_text user "License: Apache-2.0"
			(at -0.4 -5.101 90)
			(layer "B.Fab")
			(effects
				(font
					(size 0.7 0.7)
					(thickness 0.15)
				)
				(justify right top mirror)
			)
		)
		(fp_text user "Author: Antmicro"
			(at -0.4 -3.901 90)
			(layer "B.Fab")
			(effects
				(font
					(size 0.7 0.7)
					(thickness 0.15)
				)
				(justify right top mirror)
			)
		)
		(pad "1" smd circle
			(at 0 0 90)
			(size 0.75 0.75)
			(layers "B.Cu" "B.Mask")
			(net 1103 "/USB Hub/DP1_DISCH")
			(pinfunction "1")
			(pintype "passive")
		)
	)
)
